# S9S_MB_2U (Grand Teton) — schematic netlist excerpt (pin names and nets, part order shuffled) for the footprints in the layout excerpt that follows; sources: Cadence DE-HDL packaged netlist, KiCad conversion of 03242023_DA0F0TMBIJ0_F0T_Motherboard_J_brd_V01_OCP.brd

J3  SCONN288_ADR50017P130CC  SCONN288_ADR50017-P130CC IO  pkg DDR288S_1-1VXB  page 84
  VIN_BULK0  = P12V_S3_AUX_CPU0_NVDIMM
  RFU0  = TP_CHB_CPU0_DIMM1_FRU_0
  VIN_MGMT  = P3V3_AUX
  HSCL  = I3C_SPD_DDRABCD_CPU0_LVC1_SCL_2
  HSDA  = I3C_SPD_DDRABCD_CPU0_LVC1_SDA
  VSS0  = GND
  DQ0_A  = M_B_CPU0_SA_DQ<0>
  VSS1  = GND
  DQ1_A  = M_B_CPU0_SA_DQ<1>
  VSS2  = GND
  DQS0_A_T  = M_B_CPU0_SA_DQS_DP<0>
  DQS0_A_C  = M_B_CPU0_SA_DQS_DN<0>
  VSS3  = GND
  DQ4_A  = M_B_CPU0_SA_DQ<4>
  VSS4  = GND
  DQ5_A  = M_B_CPU0_SA_DQ<5>
  VSS5  = GND
  DQ8_A  = M_B_CPU0_SA_DQ<8>
  VSS6  = GND
  DQ9_A  = M_B_CPU0_SA_DQ<9>
  VSS7  = GND
  DQS1_A_T  = M_B_CPU0_SA_DQS_DP<1>
  DQS1_A_C  = M_B_CPU0_SA_DQS_DN<1>
  VSS8  = GND
  DQ12_A  = M_B_CPU0_SA_DQ<12>
  VSS9  = GND
  DQ13_A  = M_B_CPU0_SA_DQ<13>
  VSS10  = GND
  DQ16_A  = M_B_CPU0_SA_DQ<16>
  VSS11  = GND
  DQ17_A  = M_B_CPU0_SA_DQ<17>
  VSS12  = GND
  DQS2_A_T  = M_B_CPU0_SA_DQS_DP<2>
  DQS2_A_C  = M_B_CPU0_SA_DQS_DN<2>
  VSS13  = GND
  DQ20_A  = M_B_CPU0_SA_DQ<20>
  VSS14  = GND
  DQ21_A  = M_B_CPU0_SA_DQ<21>
  VSS15  = GND
  DQ24_A  = M_B_CPU0_SA_DQ<24>
  VSS16  = GND
  DQ25_A  = M_B_CPU0_SA_DQ<25>
  VSS17  = GND
  DQS3_A_T  = M_B_CPU0_SA_DQS_DP<3>
  DQS3_A_C  = M_B_CPU0_SA_DQS_DN<3>
  VSS18  = GND
  DQ28_A  = M_B_CPU0_SA_DQ<28>
  VSS19  = GND
  DQ29_A  = M_B_CPU0_SA_DQ<29>
  VSS20  = GND
  CB0_A  = M_B_CPU0_SA_CB<0>
  VSS21  = GND
  CB1_A  = M_B_CPU0_SA_CB<1>
  VSS22  = GND
  DQS4_A_T  = M_B_CPU0_SA_DQS_DP<4>
  DQS4_A_C  = M_B_CPU0_SA_DQS_DN<4>
  VSS23  = GND
  CB4_A  = M_B_CPU0_SA_CB<4>
  VSS24  = GND
  CB5_A  = M_B_CPU0_SA_CB<5>
  VSS25  = GND
  ALERT_N  = M_B_CPU0_ALERT_N
  VSS26  = GND
  CS0_A_N  = M_B_CPU0_SA_CS_N<0>
  VSS27  = GND
  CA0_A  = M_B_CPU0_SA_CA<0>
  VSS28  = GND
  CA2_A  = M_B_CPU0_SA_CA<2>
  VSS29  = GND
  CA4_A  = M_B_CPU0_SA_CA<4>
  VSS30  = GND
  CA6_A  = M_B_CPU0_SA_CA<6>
  VSS31  = GND
  PAR_A  = M_B_CPU0_SA_PAR
  VSS32  = GND
  CA0_B  = M_B_CPU0_SB_CA<0>
  VSS33  = GND
  CA2_B  = M_B_CPU0_SB_CA<2>
  VSS34  = GND
  CA4_B  = M_B_CPU0_SB_CA<4>
  VSS35  = GND
  CA6_B  = M_B_CPU0_SB_CA<6>
  VSS36  = GND
  CS0_B_N  = M_B_CPU0_SB_CS_N<0>
  VSS37  = GND
  \lbd||rsp_a_n\  = M_B_CPU0_SA_RSP<0>
  \lbs||rsp_b_n\  = M_B_CPU0_SB_RSP<0>
  VSS38  = GND
  CB4_B  = M_B_CPU0_SB_CB<4>
  VSS39  = GND
  CB5_B  = M_B_CPU0_SB_CB<5>
  VSS40  = GND
  \dqs9_b_t||tdqs9_b_t||dbi4_b_n\  = M_B_CPU0_SB_DQS_DP<9>
  \dqs9_b_c||tdqs9_b_c\  = M_B_CPU0_SB_DQS_DN<9>
  VSS41  = GND
  CB0_B  = M_B_CPU0_SB_CB<0>
  VSS42  = GND
  CB1_B  = M_B_CPU0_SB_CB<1>
  VSS43  = GND
  DQ0_B  = M_B_CPU0_SB_DQ<0>
  VSS44  = GND
  DQ1_B  = M_B_CPU0_SB_DQ<1>
  VSS45  = GND
  DQS0_B_T  = M_B_CPU0_SB_DQS_DP<0>
  DQS0_B_C  = M_B_CPU0_SB_DQS_DN<0>
  VSS46  = GND
  DQ4_B  = M_B_CPU0_SB_DQ<4>
  VSS47  = GND
  DQ5_B  = M_B_CPU0_SB_DQ<5>
  VSS48  = GND
  DQ8_B  = M_B_CPU0_SB_DQ<8>
  VSS49  = GND
  DQ9_B  = M_B_CPU0_SB_DQ<9>
  VSS50  = GND
  DQS1_B_T  = M_B_CPU0_SB_DQS_DP<1>
  DQS1_B_C  = M_B_CPU0_SB_DQS_DN<1>
  VSS51  = GND
  DQ12_B  = M_B_CPU0_SB_DQ<12>
  VSS52  = GND
  DQ13_B  = M_B_CPU0_SB_DQ<13>
  VSS53  = GND
  DQ16_B  = M_B_CPU0_SB_DQ<16>
  VSS54  = GND
  DQ17_B  = M_B_CPU0_SB_DQ<17>
  VSS55  = GND
  DQS2_B_T  = M_B_CPU0_SB_DQS_DP<2>
  DQS2_B_C  = M_B_CPU0_SB_DQS_DN<2>
  VSS56  = GND
  DQ20_B  = M_B_CPU0_SB_DQ<20>
  VSS57  = GND
  DQ21_B  = M_B_CPU0_SB_DQ<21>
  VSS58  = GND
  DQ24_B  = M_B_CPU0_SB_DQ<24>
  VSS59  = GND
  DQ25_B  = M_B_CPU0_SB_DQ<25>
  VSS60  = GND
  DQS3_B_T  = M_B_CPU0_SB_DQS_DP<3>
  DQS3_B_C  = M_B_CPU0_SB_DQS_DN<3>
  VSS61  = GND
  DQ28_B  = M_B_CPU0_SB_DQ<28>
  VSS62  = GND
  DQ29_B  = M_B_CPU0_SB_DQ<29>
  VSS63  = GND
  RFU1  = TP_CHB_CPU0_DIMM1_FRU_1
  VIN_BULK1  = P12V_S3_AUX_CPU0_NVDIMM
  VIN_BULK2  = P12V_S3_AUX_CPU0_NVDIMM
  \pwr_good||fail_n\  = PWRGD_CHB_CPU0_DIMM1
  HSA  = PD_CHB_CPU0_DIMM1_SAA
  RFU2  = TP_CHB_CPU0_DIMM1_FRU_2
  RFU3  = TP_CHB_CPU0_DIMM1_FRU_3
  VSS64  = GND
  DQ2_A  = M_B_CPU0_SA_DQ<2>
  VSS65  = GND
  DQ3_A  = M_B_CPU0_SA_DQ<3>
  VSS66  = GND
  \dqs5_a_c||tdqs5_a_c||dqs5_a_t||tdqs5_a_t\  = M_B_CPU0_SA_DQS_DN<5>
  \dqs5_a_t||tdqs5_a_t\  = M_B_CPU0_SA_DQS_DP<5>
  VSS67  = GND
  DQ6_A  = M_B_CPU0_SA_DQ<6>
  VSS68  = GND
  DQ7_A  = M_B_CPU0_SA_DQ<7>
  VSS69  = GND
  DQ10_A  = M_B_CPU0_SA_DQ<10>
  VSS70  = GND
  DQ11_A  = M_B_CPU0_SA_DQ<11>
  VSS71  = GND
  \dqs6_a_c||tdqs6_a_c||dqs6_a_t||tdqs6_a_t\  = M_B_CPU0_SA_DQS_DN<6>
  \dqs6_a_t||tdqs6_a_t\  = M_B_CPU0_SA_DQS_DP<6>
  VSS72  = GND
  DQ14_A  = M_B_CPU0_SA_DQ<14>
  VSS73  = GND
  DQ15_A  = M_B_CPU0_SA_DQ<15>
  VSS74  = GND
  DQ18_A  = M_B_CPU0_SA_DQ<18>
  VSS75  = GND
  DQ19_A  = M_B_CPU0_SA_DQ<19>
  VSS76  = GND
  \dqs7_a_c||tdqs7_a_c\  = M_B_CPU0_SA_DQS_DN<7>
  \dqs7_a_t||tdqs7_a_t\  = M_B_CPU0_SA_DQS_DP<7>
  VSS77  = GND
  DQ22_A  = M_B_CPU0_SA_DQ<22>
  VSS78  = GND
  DQ23_A  = M_B_CPU0_SA_DQ<23>
  VSS79  = GND
  DQ26_A  = M_B_CPU0_SA_DQ<26>
  VSS80  = GND
  DQ27_A  = M_B_CPU0_SA_DQ<27>
  VSS81  = GND
  \dqs8_a_c||tdqs8_a_c\  = M_B_CPU0_SA_DQS_DN<8>
  \dqs8_a_t||tdqs8_a_t\  = M_B_CPU0_SA_DQS_DP<8>
  VSS82  = GND
  DQ30_A  = M_B_CPU0_SA_DQ<30>
  VSS83  = GND
  DQ31_A  = M_B_CPU0_SA_DQ<31>
  VSS84  = GND
  CB2_A  = M_B_CPU0_SA_CB<2>
  VSS85  = GND
  CB3_A  = M_B_CPU0_SA_CB<3>
  VSS86  = GND
  \dqs9_a_c||tdqs9_a_c\  = M_B_CPU0_SA_DQS_DN<9>
  \dqs9_a_t||tdqs9_a_t\  = M_B_CPU0_SA_DQS_DP<9>
  VSS87  = GND
  CB6_A  = M_B_CPU0_SA_CB<6>
  VSS88  = GND
  CB7_A  = M_B_CPU0_SA_CB<7>
  VSS89  = GND
  RESET_N  = RST_M_AB_CPU0_FPGA_N
  VSS90  = GND
  CS1_A_N  = M_B_CPU0_SA_CS_N<1>
  VSS91  = GND
  CA1_A  = M_B_CPU0_SA_CA<1>
  VSS92  = GND
  CA3_A  = M_B_CPU0_SA_CA<3>
  VSS93  = GND
  CA5_A  = M_B_CPU0_SA_CA<5>
  VSS94  = GND
  CK_T  = M_B_CPU0_CLK_DP<0>
  CK_C  = M_B_CPU0_CLK_DN<0>
  VSS95  = GND
  RFU4  = TP_CHB_CPU0_DIMM1_FRU_4
  CA1_B  = M_B_CPU0_SB_CA<1>
  VSS96  = GND
  CA3_B  = M_B_CPU0_SB_CA<3>
  VSS97  = GND
  CA5_B  = M_B_CPU0_SB_CA<5>
  VSS98  = GND
  PAR_B  = M_B_CPU0_SB_PAR
  VSS99  = GND
  CS1_B_N  = M_B_CPU0_SB_CS_N<1>
  VSS100  = GND
  RFU5  = TP_CHB_CPU0_DIMM1_FRU_5
  RFU6  = TP_CHB_CPU0_DIMM1_FRU_6
  VSS101  = GND
  CB6_B  = M_B_CPU0_SB_CB<6>
  VSS102  = GND
  CB7_B  = M_B_CPU0_SB_CB<7>
  VSS103  = GND
  DQS4_B_C  = M_B_CPU0_SB_DQS_DN<4>
  DQS4_B_T  = M_B_CPU0_SB_DQS_DP<4>
  VSS104  = GND
  CB2_B  = M_B_CPU0_SB_CB<2>
  VSS105  = GND
  CB3_B  = M_B_CPU0_SB_CB<3>
  VSS106  = GND
  DQ2_B  = M_B_CPU0_SB_DQ<2>
  VSS107  = GND
  DQ3_B  = M_B_CPU0_SB_DQ<3>
  VSS108  = GND
  \dqs5_b_c||tdqs5_b_c\  = M_B_CPU0_SB_DQS_DN<5>
  \dqs5_b_t||tdqs5_b_t\  = M_B_CPU0_SB_DQS_DP<5>
  VSS109  = GND
  DQ6_B  = M_B_CPU0_SB_DQ<6>
  VSS110  = GND
  DQ7_B  = M_B_CPU0_SB_DQ<7>
  VSS111  = GND
  DQ10_B  = M_B_CPU0_SB_DQ<10>
  VSS112  = GND
  DQ11_B  = M_B_CPU0_SB_DQ<11>
  VSS113  = GND
  \dqs6_b_c||tdqs6_b_c\  = M_B_CPU0_SB_DQS_DN<6>
  \dqs6_b_t||tdqs6_b_t\  = M_B_CPU0_SB_DQS_DP<6>
  VSS114  = GND
  DQ14_B  = M_B_CPU0_SB_DQ<14>
  VSS115  = GND
  DQ15_B  = M_B_CPU0_SB_DQ<15>
  VSS116  = GND
  DQ18_B  = M_B_CPU0_SB_DQ<18>
  VSS117  = GND
  DQ19_B  = M_B_CPU0_SB_DQ<19>
  VSS118  = GND
  \dqs7_b_c||tdqs7_b_c\  = M_B_CPU0_SB_DQS_DN<7>
  \dqs7_b_t||tdqs7_b_t\  = M_B_CPU0_SB_DQS_DP<7>
  VSS119  = GND
  DQ22_B  = M_B_CPU0_SB_DQ<22>
  VSS120  = GND
  DQ23_B  = M_B_CPU0_SB_DQ<23>
  VSS121  = GND
  DQ26_B  = M_B_CPU0_SB_DQ<26>
  VSS122  = GND
  DQ27_B  = M_B_CPU0_SB_DQ<27>
  VSS123  = GND
  \dqs8_b_c||tdqs8_b_c\  = M_B_CPU0_SB_DQS_DN<8>
  \dqs8_b_t||tdqs8_b_t\  = M_B_CPU0_SB_DQS_DP<8>
  VSS124  = GND
  DQ30_B  = M_B_CPU0_SB_DQ<30>
  VSS125  = GND
  DQ31_B  = M_B_CPU0_SB_DQ<31>
  VSS126  = GND
  G1  = GND
  G2  = GND
  G3  = GND

(kicad_pcb
	(version 20260206)
	(generator "pcbnew")
	(generator_version "10.0")
	(general
		(thickness 1.6)
		(legacy_teardrops no)
	)
	(paper "A4")
	(title_block
		(title "03242023_DA0F0TMBIJ0_F0T_Motherboard_J_brd_V01_OCP.brd")
		(comment 1 "Grand Teton / footprint 2048 of 6105 (J3), pads 46-91 of 291")
	)
	(layers
		(0 "F.Cu" signal "TOP")
		(4 "In1.Cu" signal "GND")
		(6 "In2.Cu" signal "IN1")
		(8 "In3.Cu" signal "GND1")
		(10 "In4.Cu" signal "IN2")
		(12 "In5.Cu" signal "GND2")
		(14 "In6.Cu" signal "IN3")
		(16 "In7.Cu" signal "GND3")
		(18 "In8.Cu" signal "VCC")
		(20 "In9.Cu" signal "VCC1")
		(22 "In10.Cu" signal "GND4")
		(24 "In11.Cu" signal "IN4")
		(26 "In12.Cu" signal "GND5")
		(28 "In13.Cu" signal "IN5")
		(30 "In14.Cu" signal "GND6")
		(32 "In15.Cu" signal "IN6")
		(34 "In16.Cu" signal "GND7")
		(2 "B.Cu" signal "BOTTOM")
		(9 "F.Adhes" user "F.Adhesive")
		(11 "B.Adhes" user "B.Adhesive")
		(13 "F.Paste" user "Package Geometry/Pastemask Top")
		(15 "B.Paste" user "Package Geometry/Pastemask Bottom")
		(5 "F.SilkS" user "Ref Des/Silkscreen Top")
		(7 "B.SilkS" user "Ref Des/Silkscreen Bottom")
		(1 "F.Mask" user "Board Geometry/Soldermask Top")
		(3 "B.Mask" user "Board Geometry/Soldermask Bottom")
		(17 "Dwgs.User" user "User.Drawings")
		(19 "Cmts.User" user "User.Comments")
		(21 "Eco1.User" user "User.Eco1")
		(23 "Eco2.User" user "User.Eco2")
		(25 "Edge.Cuts" user "Board Geometry/Outline")
		(27 "Margin" user)
		(31 "F.CrtYd" user "Package Geometry/Place Bound Top")
		(29 "B.CrtYd" user "Package Geometry/Place Bound Bottom")
		(35 "F.Fab" user "Ref Des/Assembly Top")
		(33 "B.Fab" user "Ref Des/Assembly Bottom")
	)
	(footprint ""
		(layer "F.Cu")
		(at 288.305748 -258.091686)
		(property "Reference" "J3"
			(at -3.683 -81.702148 0)
			(unlocked yes)
			(layer "F.SilkS")
			(effects
				(font
					(size 0.7874 0.5842)
					(thickness 0.1524)
				)
				(justify left)
			)
		)
		(property "Value" ""
			(at 0 0 0)
			(layer "F.Fab")
			(effects
				(font
					(size 1.27 1.27)
				)
			)
		)
		(duplicate_pad_numbers_are_jumpers no)
		(pad "46" smd rect
			(at -2.050034 -25.07488 270)
			(size 0.519938 1.4986)
			(layers "F.Cu" "F.Mask" "F.Paste")
			(net "GND")
		)
		(pad "47" smd rect
			(at -2.050034 -24.224996 270)
			(size 0.519938 1.4986)
			(layers "F.Cu" "F.Mask" "F.Paste")
			(net "M_B_CPU0_SA_DQ<28>")
		)
		(pad "48" smd rect
			(at -2.050034 -23.375112 270)
			(size 0.519938 1.4986)
			(layers "F.Cu" "F.Mask" "F.Paste")
			(net "GND")
		)
		(pad "49" smd rect
			(at -2.050034 -22.524974 270)
			(size 0.519938 1.4986)
			(layers "F.Cu" "F.Mask" "F.Paste")
			(net "M_B_CPU0_SA_DQ<29>")
		)
		(pad "50" smd rect
			(at -2.050034 -21.67509 270)
			(size 0.519938 1.4986)
			(layers "F.Cu" "F.Mask" "F.Paste")
			(net "GND")
		)
		(pad "51" smd rect
			(at -2.050034 -20.824952 270)
			(size 0.519938 1.4986)
			(layers "F.Cu" "F.Mask" "F.Paste")
			(net "M_B_CPU0_SA_CB<0>")
		)
		(pad "52" smd rect
			(at -2.050034 -19.975068 270)
			(size 0.519938 1.4986)
			(layers "F.Cu" "F.Mask" "F.Paste")
			(net "GND")
		)
		(pad "53" smd rect
			(at -2.050034 -19.12493 270)
			(size 0.519938 1.4986)
			(layers "F.Cu" "F.Mask" "F.Paste")
			(net "M_B_CPU0_SA_CB<1>")
		)
		(pad "54" smd rect
			(at -2.050034 -18.275046 270)
			(size 0.519938 1.4986)
			(layers "F.Cu" "F.Mask" "F.Paste")
			(net "GND")
		)
		(pad "55" smd rect
			(at -2.050034 -17.424908 270)
			(size 0.519938 1.4986)
			(layers "F.Cu" "F.Mask" "F.Paste")
			(net "M_B_CPU0_SA_DQS_DP<4>")
		)
		(pad "56" smd rect
			(at -2.050034 -16.575024 270)
			(size 0.519938 1.4986)
			(layers "F.Cu" "F.Mask" "F.Paste")
			(net "M_B_CPU0_SA_DQS_DN<4>")
		)
		(pad "57" smd rect
			(at -2.050034 -15.724886 270)
			(size 0.519938 1.4986)
			(layers "F.Cu" "F.Mask" "F.Paste")
			(net "GND")
		)
		(pad "58" smd rect
			(at -2.050034 -14.875002 270)
			(size 0.519938 1.4986)
			(layers "F.Cu" "F.Mask" "F.Paste")
			(net "M_B_CPU0_SA_CB<4>")
		)
		(pad "59" smd rect
			(at -2.050034 -14.025118 270)
			(size 0.519938 1.4986)
			(layers "F.Cu" "F.Mask" "F.Paste")
			(net "GND")
		)
		(pad "60" smd rect
			(at -2.050034 -13.17498 270)
			(size 0.519938 1.4986)
			(layers "F.Cu" "F.Mask" "F.Paste")
			(net "M_B_CPU0_SA_CB<5>")
		)
		(pad "61" smd rect
			(at -2.050034 -12.325096 270)
			(size 0.519938 1.4986)
			(layers "F.Cu" "F.Mask" "F.Paste")
			(net "GND")
		)
		(pad "62" smd rect
			(at -2.050034 -11.474958 270)
			(size 0.519938 1.4986)
			(layers "F.Cu" "F.Mask" "F.Paste")
			(net "M_B_CPU0_ALERT_N")
		)
		(pad "63" smd rect
			(at -2.050034 -10.625074 270)
			(size 0.519938 1.4986)
			(layers "F.Cu" "F.Mask" "F.Paste")
			(net "GND")
		)
		(pad "64" smd rect
			(at -2.050034 -9.774936 270)
			(size 0.519938 1.4986)
			(layers "F.Cu" "F.Mask" "F.Paste")
			(net "M_B_CPU0_SA_CS_N<0>")
		)
		(pad "65" smd rect
			(at -2.050034 -8.925052 270)
			(size 0.519938 1.4986)
			(layers "F.Cu" "F.Mask" "F.Paste")
			(net "GND")
		)
		(pad "66" smd rect
			(at -2.050034 -8.074914 270)
			(size 0.519938 1.4986)
			(layers "F.Cu" "F.Mask" "F.Paste")
			(net "M_B_CPU0_SA_CA<0>")
		)
		(pad "67" smd rect
			(at -2.050034 -7.22503 270)
			(size 0.519938 1.4986)
			(layers "F.Cu" "F.Mask" "F.Paste")
			(net "GND")
		)
		(pad "68" smd rect
			(at -2.050034 -6.374892 270)
			(size 0.519938 1.4986)
			(layers "F.Cu" "F.Mask" "F.Paste")
			(net "M_B_CPU0_SA_CA<2>")
		)
		(pad "69" smd rect
			(at -2.050034 -5.525008 270)
			(size 0.519938 1.4986)
			(layers "F.Cu" "F.Mask" "F.Paste")
			(net "GND")
		)
		(pad "70" smd rect
			(at -2.050034 -4.675124 270)
			(size 0.519938 1.4986)
			(layers "F.Cu" "F.Mask" "F.Paste")
			(net "M_B_CPU0_SA_CA<4>")
		)
		(pad "71" smd rect
			(at -2.050034 -3.824986 270)
			(size 0.519938 1.4986)
			(layers "F.Cu" "F.Mask" "F.Paste")
			(net "GND")
		)
		(pad "72" smd rect
			(at -2.050034 -2.975102 270)
			(size 0.519938 1.4986)
			(layers "F.Cu" "F.Mask" "F.Paste")
			(net "M_B_CPU0_SA_CA<6>")
		)
		(pad "73" smd rect
			(at -2.050034 -2.124964 270)
			(size 0.519938 1.4986)
			(layers "F.Cu" "F.Mask" "F.Paste")
			(net "GND")
		)
		(pad "74" smd rect
			(at -2.050034 -1.27508 270)
			(size 0.519938 1.4986)
			(layers "F.Cu" "F.Mask" "F.Paste")
			(net "M_B_CPU0_SA_PAR")
		)
		(pad "75" smd rect
			(at -2.050034 -0.424942 270)
			(size 0.519938 1.4986)
			(layers "F.Cu" "F.Mask" "F.Paste")
			(net "GND")
		)
		(pad "76" smd rect
			(at -2.050034 5.525008 270)
			(size 0.519938 1.4986)
			(layers "F.Cu" "F.Mask" "F.Paste")
			(net "M_B_CPU0_SB_CA<0>")
		)
		(pad "77" smd rect
			(at -2.050034 6.374892 270)
			(size 0.519938 1.4986)
			(layers "F.Cu" "F.Mask" "F.Paste")
			(net "GND")
		)
		(pad "78" smd rect
			(at -2.050034 7.22503 270)
			(size 0.519938 1.4986)
			(layers "F.Cu" "F.Mask" "F.Paste")
			(net "M_B_CPU0_SB_CA<2>")
		)
		(pad "79" smd rect
			(at -2.050034 8.074914 270)
			(size 0.519938 1.4986)
			(layers "F.Cu" "F.Mask" "F.Paste")
			(net "GND")
		)
		(pad "80" smd rect
			(at -2.050034 8.925052 270)
			(size 0.519938 1.4986)
			(layers "F.Cu" "F.Mask" "F.Paste")
			(net "M_B_CPU0_SB_CA<4>")
		)
		(pad "81" smd rect
			(at -2.050034 9.774936 270)
			(size 0.519938 1.4986)
			(layers "F.Cu" "F.Mask" "F.Paste")
			(net "GND")
		)
		(pad "82" smd rect
			(at -2.050034 10.625074 270)
			(size 0.519938 1.4986)
			(layers "F.Cu" "F.Mask" "F.Paste")
			(net "M_B_CPU0_SB_CA<6>")
		)
		(pad "83" smd rect
			(at -2.050034 11.474958 270)
			(size 0.519938 1.4986)
			(layers "F.Cu" "F.Mask" "F.Paste")
			(net "GND")
		)
		(pad "84" smd rect
			(at -2.050034 12.325096 270)
			(size 0.519938 1.4986)
			(layers "F.Cu" "F.Mask" "F.Paste")
			(net "M_B_CPU0_SB_CS_N<0>")
		)
		(pad "85" smd rect
			(at -2.050034 13.17498 270)
			(size 0.519938 1.4986)
			(layers "F.Cu" "F.Mask" "F.Paste")
			(net "GND")
		)
		(pad "86" smd rect
			(at -2.050034 14.025118 270)
			(size 0.519938 1.4986)
			(layers "F.Cu" "F.Mask" "F.Paste")
			(net "M_B_CPU0_SA_RSP<0>")
		)
		(pad "87" smd rect
			(at -2.050034 14.875002 270)
			(size 0.519938 1.4986)
			(layers "F.Cu" "F.Mask" "F.Paste")
			(net "M_B_CPU0_SB_RSP<0>")
		)
		(pad "88" smd rect
			(at -2.050034 15.724886 270)
			(size 0.519938 1.4986)
			(layers "F.Cu" "F.Mask" "F.Paste")
			(net "GND")
		)
		(pad "89" smd rect
			(at -2.050034 16.575024 270)
			(size 0.519938 1.4986)
			(layers "F.Cu" "F.Mask" "F.Paste")
			(net "M_B_CPU0_SB_CB<4>")
		)
		(pad "90" smd rect
			(at -2.050034 17.424908 270)
			(size 0.519938 1.4986)
			(layers "F.Cu" "F.Mask" "F.Paste")
			(net "GND")
		)
		(pad "91" smd rect
			(at -2.050034 18.275046 270)
			(size 0.519938 1.4986)
			(layers "F.Cu" "F.Mask" "F.Paste")
			(net "M_B_CPU0_SB_CB<5>")
		)
	)
)
